FILE_TYPE = MULTI_PHYS_TABLE;

PART 'CAT93C46VI_GT3_SOIC8'
CLASS=IC

{========================================================================================}
:CLS_PN          = JEDEC_TYPE         | ALT_SYMBOLS          | DESCRIPTION                                                        | CPN_STATUS ;
{========================================================================================}
 'G221-10167-01' = 'SOP8_154_P050_V1' | '(SOP8_154_P050_V1)' | 'IC, CAT93C46VI-GT3, 1KB MICROWIRE SERIAL EEPROM, -40~85C, SOIC-8' | 'OBSOLETE'
 'G221-10262-01' = 'SOP8_154_P050_V1' | '(SOP8_154_P050_V1)' | 'IC,EEPROM,16KBIT,2MHZ,8PIN,SOIC'                                  | ''        
 'G221-10075-01' = 'SOP8_154_P050_V1' | '(SOP8_154_P050_V1)' | 'IC,AT93C46D,1KBIT,THREE-WIRE EEPROM,1.8V-5.5V,SO8'                | ''        
 'G221-10075-02' = 'SOP8_154_P050_V1' | '(SOP8_154_P050_V1)' | 'IC,AT93C46D,1KBIT,THREE-WIRE EEPROM,1.8V-5.5V,SO8'                | ''        

END_PART

END.

